(kicad_pcb
	(version 20260206)
	(generator "pcbnew")
	(generator_version "10.0")
	(general
		(thickness 1.6)
		(legacy_teardrops no)
	)
	(paper "A4")
	(title_block
		(title "9054_F0T_PDB_BD_GPU_F_V04_1213_1550_OCP.brd")
		(comment 1 "Grand Teton / footprints 323-324 of 608")
	)
	(layers
		(0 "F.Cu" signal "TOP")
		(4 "In1.Cu" signal "GND")
		(6 "In2.Cu" signal "IN1")
		(8 "In3.Cu" signal "GND1")
		(10 "In4.Cu" signal "VCC")
		(12 "In5.Cu" signal "VCC1")
		(14 "In6.Cu" signal "GND2")
		(16 "In7.Cu" signal "IN2")
		(18 "In8.Cu" signal "GND3")
		(2 "B.Cu" signal "BOTTOM")
		(9 "F.Adhes" user "F.Adhesive")
		(11 "B.Adhes" user "B.Adhesive")
		(13 "F.Paste" user "Package Geometry/Pastemask Top")
		(15 "B.Paste" user "Package Geometry/Pastemask Bottom")
		(5 "F.SilkS" user "Ref Des/Silkscreen Top")
		(7 "B.SilkS" user "Ref Des/Silkscreen Bottom")
		(1 "F.Mask" user "Board Geometry/Soldermask Top")
		(3 "B.Mask" user "Board Geometry/Soldermask Bottom")
		(17 "Dwgs.User" user "User.Drawings")
		(19 "Cmts.User" user "User.Comments")
		(21 "Eco1.User" user "User.Eco1")
		(23 "Eco2.User" user "User.Eco2")
		(25 "Edge.Cuts" user "Board Geometry/Outline")
		(27 "Margin" user)
		(31 "F.CrtYd" user "Package Geometry/Place Bound Top")
		(29 "B.CrtYd" user "Package Geometry/Place Bound Bottom")
		(35 "F.Fab" user "Ref Des/Assembly Top")
		(33 "B.Fab" user "Ref Des/Assembly Bottom")
	)
	(footprint ""
		(layer "F.Cu")
		(at 208.810098 -51.049936 180)
		(property "Reference" "J7"
			(at 9.775698 -41.778936 0)
			(unlocked yes)
			(layer "F.SilkS")
			(effects
				(font
					(size 10.16 7.62)
					(thickness 1.778)
				)
			)
		)
		(property "Value" ""
			(at 0 0 180)
			(layer "F.Fab")
			(effects
				(font
					(size 1.27 1.27)
				)
			)
		)
		(duplicate_pad_numbers_are_jumpers no)
		(fp_line
			(start 14.109954 34.36493)
			(end -6.469888 34.36493)
			(stroke
				(width 0.1524)
				(type default)
			)
			(layer "F.SilkS")
		)
		(fp_line
			(start 14.109954 -34.36493)
			(end 14.109954 34.36493)
			(stroke
				(width 0.1524)
				(type default)
			)
			(layer "F.SilkS")
		)
		(fp_line
			(start 11.10996 31.364936)
			(end 4.213098 31.364936)
			(stroke
				(width 0.1524)
				(type default)
			)
			(layer "F.SilkS")
		)
		(fp_line
			(start 11.10996 -31.364936)
			(end 11.10996 31.364936)
			(stroke
				(width 0.1524)
				(type default)
			)
			(layer "F.SilkS")
		)
		(fp_line
			(start 4.263898 -31.364936)
			(end 11.10996 -31.364936)
			(stroke
				(width 0.1524)
				(type default)
			)
			(layer "F.SilkS")
		)
		(fp_line
			(start -3.469894 26.115264)
			(end -3.469894 -26.005536)
			(stroke
				(width 0.1524)
				(type default)
			)
			(layer "F.SilkS")
		)
		(fp_line
			(start -6.469888 34.36493)
			(end -6.469888 -34.36493)
			(stroke
				(width 0.1524)
				(type default)
			)
			(layer "F.SilkS")
		)
		(fp_line
			(start -6.469888 -34.36493)
			(end 14.109954 -34.36493)
			(stroke
				(width 0.1524)
				(type default)
			)
			(layer "F.SilkS")
		)
		(fp_poly
			(pts
				(xy -5.0038 -0.508) (xy -5.0038 0.508) (xy -3.9878 0)
			)
			(stroke
				(width 0)
				(type default)
			)
			(fill yes)
			(layer "F.SilkS")
		)
		(fp_line
			(start 14.109954 34.36493)
			(end -6.469888 34.36493)
			(stroke
				(width 0.1524)
				(type default)
			)
			(layer "B.SilkS")
		)
		(fp_line
			(start 14.109954 -34.36493)
			(end 14.109954 34.36493)
			(stroke
				(width 0.1524)
				(type default)
			)
			(layer "B.SilkS")
		)
		(fp_line
			(start -6.469888 34.36493)
			(end -6.469888 -34.36493)
			(stroke
				(width 0.1524)
				(type default)
			)
			(layer "B.SilkS")
		)
		(fp_line
			(start -6.469888 -34.36493)
			(end 14.109954 -34.36493)
			(stroke
				(width 0.1524)
				(type default)
			)
			(layer "B.SilkS")
		)
		(fp_line
			(start 14.109954 34.36493)
			(end -6.469888 34.36493)
			(stroke
				(width 0.1)
				(type default)
			)
			(layer "B.Fab")
		)
		(fp_line
			(start 14.109954 -34.36493)
			(end 14.109954 34.36493)
			(stroke
				(width 0.1)
				(type default)
			)
			(layer "B.Fab")
		)
		(fp_line
			(start -6.469888 34.36493)
			(end -6.469888 -34.36493)
			(stroke
				(width 0.1)
				(type default)
			)
			(layer "B.Fab")
		)
		(fp_line
			(start -6.469888 -34.36493)
			(end 14.109954 -34.36493)
			(stroke
				(width 0.1)
				(type default)
			)
			(layer "B.Fab")
		)
		(fp_line
			(start 11.10996 31.364936)
			(end -3.469894 31.364936)
			(stroke
				(width 0.1)
				(type default)
			)
			(layer "F.Fab")
		)
		(fp_line
			(start 11.10996 -31.364936)
			(end 11.10996 31.364936)
			(stroke
				(width 0.1)
				(type default)
			)
			(layer "F.Fab")
		)
		(fp_line
			(start -3.469894 31.364936)
			(end -3.469894 -31.364936)
			(stroke
				(width 0.1)
				(type default)
			)
			(layer "F.Fab")
		)
		(fp_line
			(start -3.469894 -31.364936)
			(end 11.10996 -31.364936)
			(stroke
				(width 0.1)
				(type default)
			)
			(layer "F.Fab")
		)
		(fp_poly
			(pts
				(xy -5.0038 -0.508) (xy -5.0038 0.508) (xy -3.9878 0)
			)
			(stroke
				(width 0)
				(type default)
			)
			(fill yes)
			(layer "F.Fab")
		)
		(fp_text user "PRESS-FIT"
			(at 12.63015 -0.0127 90)
			(unlocked yes)
			(layer "F.SilkS")
			(effects
				(font
					(size 1.905 1.4224)
					(thickness 0.1524)
				)
			)
		)
		(fp_text user "PRESS-FIT"
			(at 12.855448 0.639064 270)
			(unlocked yes)
			(layer "B.SilkS")
			(effects
				(font
					(size 1.905 1.4224)
					(thickness 0.1524)
				)
				(justify mirror)
			)
		)
		(fp_text user "PRESS-FIT"
			(at 12.63015 -0.0127 90)
			(unlocked yes)
			(layer "B.Fab")
			(effects
				(font
					(size 1.905 1.4224)
					(thickness 0.1524)
				)
				(justify mirror)
			)
		)
		(fp_text user "PRESS-FIT"
			(at 12.63015 -0.0127 90)
			(unlocked yes)
			(layer "F.Fab")
			(effects
				(font
					(size 1.905 1.4224)
					(thickness 0.1524)
				)
			)
		)
		(pad "" np_thru_hole circle
			(at 0 -28.575 180)
			(size 0 0)
			(drill 3.2004)
			(layers "*.Cu" "*.Mask")
			(clearance 0)
		)
		(pad "" np_thru_hole circle
			(at 0 28.575 180)
			(size 0 0)
			(drill 3.2004)
			(layers "*.Cu" "*.Mask")
			(clearance 0)
		)
		(pad "A1" thru_hole rect
			(at 0 0 180)
			(size 1.52781 1.52781)
			(drill 1.01981)
			(layers "*.Cu" "*.Mask")
			(remove_unused_layers no)
			(net "P52V_2_BUSBAR")
			(clearance 0)
			(padstack
				(mode front_inner_back)
				(layer "Inner"
					(shape circle)
					(size 1.52781 1.52781)
					(clearance 0)
				)
				(layer "B.Cu"
					(shape rect)
					(size 1.52781 1.52781)
					(clearance 0)
				)
			)
		)
		(pad "B1" thru_hole circle
			(at 2.54 0 180)
			(size 1.52781 1.52781)
			(drill 1.01981)
			(layers "*.Cu" "*.Mask")
			(remove_unused_layers no)
			(net "GND_2_BUSBAR")
			(clearance 0)
		)
		(pad "C1" thru_hole circle
			(at 5.08 0 180)
			(size 1.52781 1.52781)
			(drill 1.01981)
			(layers "*.Cu" "*.Mask")
			(remove_unused_layers no)
			(net "NC_J7_C1")
			(clearance 0)
		)
		(pad "D1" thru_hole circle
			(at 7.62 0 180)
			(size 1.52781 1.52781)
			(drill 1.01981)
			(layers "*.Cu" "*.Mask")
			(remove_unused_layers no)
			(net "NC_J7_D1")
			(clearance 0)
		)
		(pad "P1_1" thru_hole circle
			(at 7.62 -16.51 180)
			(size 1.52781 1.52781)
			(drill 1.01981)
			(layers "*.Cu" "*.Mask")
			(remove_unused_layers no)
			(net "P52V_2")
			(clearance 0)
		)
		(pad "P1_2" thru_hole circle
			(at 5.08 -16.51 180)
			(size 1.52781 1.52781)
			(drill 1.01981)
			(layers "*.Cu" "*.Mask")
			(remove_unused_layers no)
			(net "P52V_2")
			(clearance 0)
		)
		(pad "P1_3" thru_hole circle
			(at 2.54 -16.51 180)
			(size 1.52781 1.52781)
			(drill 1.01981)
			(layers "*.Cu" "*.Mask")
			(remove_unused_layers no)
			(net "P52V_2")
			(clearance 0)
		)
		(pad "P1_4" thru_hole circle
			(at 0 -16.51 180)
			(size 1.52781 1.52781)
			(drill 1.01981)
			(layers "*.Cu" "*.Mask")
			(remove_unused_layers no)
			(net "P52V_2")
			(clearance 0)
		)
		(pad "P1_5" thru_hole circle
			(at 7.62 -13.97 180)
			(size 1.52781 1.52781)
			(drill 1.01981)
			(layers "*.Cu" "*.Mask")
			(remove_unused_layers no)
			(net "P52V_2")
			(clearance 0)
		)
		(pad "P1_6" thru_hole circle
			(at 5.08 -13.97 180)
			(size 1.52781 1.52781)
			(drill 1.01981)
			(layers "*.Cu" "*.Mask")
			(remove_unused_layers no)
			(net "P52V_2")
			(clearance 0)
		)
		(pad "P1_7" thru_hole circle
			(at 2.54 -13.97 180)
			(size 1.52781 1.52781)
			(drill 1.01981)
			(layers "*.Cu" "*.Mask")
			(remove_unused_layers no)
			(net "P52V_2")
			(clearance 0)
		)
		(pad "P1_8" thru_hole circle
			(at 0 -13.97 180)
			(size 1.52781 1.52781)
			(drill 1.01981)
			(layers "*.Cu" "*.Mask")
			(remove_unused_layers no)
			(net "P52V_2")
			(clearance 0)
		)
		(pad "P2_1" thru_hole circle
			(at 7.62 -7.62 180)
			(size 1.52781 1.52781)
			(drill 1.01981)
			(layers "*.Cu" "*.Mask")
			(remove_unused_layers no)
			(net "P52V_2")
			(clearance 0)
		)
		(pad "P2_2" thru_hole circle
			(at 5.08 -7.62 180)
			(size 1.52781 1.52781)
			(drill 1.01981)
			(layers "*.Cu" "*.Mask")
			(remove_unused_layers no)
			(net "P52V_2")
			(clearance 0)
		)
		(pad "P2_3" thru_hole circle
			(at 2.54 -7.62 180)
			(size 1.52781 1.52781)
			(drill 1.01981)
			(layers "*.Cu" "*.Mask")
			(remove_unused_layers no)
			(net "P52V_2")
			(clearance 0)
		)
		(pad "P2_4" thru_hole circle
			(at 0 -7.62 180)
			(size 1.52781 1.52781)
			(drill 1.01981)
			(layers "*.Cu" "*.Mask")
			(remove_unused_layers no)
			(net "P52V_2")
			(clearance 0)
		)
		(pad "P2_5" thru_hole circle
			(at 7.62 -5.08 180)
			(size 1.52781 1.52781)
			(drill 1.01981)
			(layers "*.Cu" "*.Mask")
			(remove_unused_layers no)
			(net "P52V_2")
			(clearance 0)
		)
		(pad "P2_6" thru_hole circle
			(at 5.08 -5.08 180)
			(size 1.52781 1.52781)
			(drill 1.01981)
			(layers "*.Cu" "*.Mask")
			(remove_unused_layers no)
			(net "P52V_2")
			(clearance 0)
		)
		(pad "P2_7" thru_hole circle
			(at 2.54 -5.08 180)
			(size 1.52781 1.52781)
			(drill 1.01981)
			(layers "*.Cu" "*.Mask")
			(remove_unused_layers no)
			(net "P52V_2")
			(clearance 0)
		)
		(pad "P2_8" thru_hole circle
			(at 0 -5.08 180)
			(size 1.52781 1.52781)
			(drill 1.01981)
			(layers "*.Cu" "*.Mask")
			(remove_unused_layers no)
			(net "P52V_2")
			(clearance 0)
		)
		(pad "P3_1" thru_hole circle
			(at 7.62 5.08 180)
			(size 1.52781 1.52781)
			(drill 1.01981)
			(layers "*.Cu" "*.Mask")
			(remove_unused_layers no)
			(net "GND")
			(clearance 0)
		)
		(pad "P3_2" thru_hole circle
			(at 5.08 5.08 180)
			(size 1.52781 1.52781)
			(drill 1.01981)
			(layers "*.Cu" "*.Mask")
			(remove_unused_layers no)
			(net "GND")
			(clearance 0)
		)
		(pad "P3_3" thru_hole circle
			(at 2.54 5.08 180)
			(size 1.52781 1.52781)
			(drill 1.01981)
			(layers "*.Cu" "*.Mask")
			(remove_unused_layers no)
			(net "GND")
			(clearance 0)
		)
		(pad "P3_4" thru_hole circle
			(at 0 5.08 180)
			(size 1.52781 1.52781)
			(drill 1.01981)
			(layers "*.Cu" "*.Mask")
			(remove_unused_layers no)
			(net "GND")
			(clearance 0)
		)
		(pad "P3_5" thru_hole circle
			(at 7.62 7.62 180)
			(size 1.52781 1.52781)
			(drill 1.01981)
			(layers "*.Cu" "*.Mask")
			(remove_unused_layers no)
			(net "GND")
			(clearance 0)
		)
		(pad "P3_6" thru_hole circle
			(at 5.08 7.62 180)
			(size 1.52781 1.52781)
			(drill 1.01981)
			(layers "*.Cu" "*.Mask")
			(remove_unused_layers no)
			(net "GND")
			(clearance 0)
		)
		(pad "P3_7" thru_hole circle
			(at 2.54 7.62 180)
			(size 1.52781 1.52781)
			(drill 1.01981)
			(layers "*.Cu" "*.Mask")
			(remove_unused_layers no)
			(net "GND")
			(clearance 0)
		)
		(pad "P3_8" thru_hole circle
			(at 0 7.62 180)
			(size 1.52781 1.52781)
			(drill 1.01981)
			(layers "*.Cu" "*.Mask")
			(remove_unused_layers no)
			(net "GND")
			(clearance 0)
		)
		(pad "P4_1" thru_hole circle
			(at 7.62 13.97 180)
			(size 1.52781 1.52781)
			(drill 1.01981)
			(layers "*.Cu" "*.Mask")
			(remove_unused_layers no)
			(net "GND")
			(clearance 0)
		)
		(pad "P4_2" thru_hole circle
			(at 5.08 13.97 180)
			(size 1.52781 1.52781)
			(drill 1.01981)
			(layers "*.Cu" "*.Mask")
			(remove_unused_layers no)
			(net "GND")
			(clearance 0)
		)
		(pad "P4_3" thru_hole circle
			(at 2.54 13.97 180)
			(size 1.52781 1.52781)
			(drill 1.01981)
			(layers "*.Cu" "*.Mask")
			(remove_unused_layers no)
			(net "GND")
			(clearance 0)
		)
		(pad "P4_4" thru_hole circle
			(at 0 13.97 180)
			(size 1.52781 1.52781)
			(drill 1.01981)
			(layers "*.Cu" "*.Mask")
			(remove_unused_layers no)
			(net "GND")
			(clearance 0)
		)
		(pad "P4_5" thru_hole circle
			(at 7.62 16.51 180)
			(size 1.52781 1.52781)
			(drill 1.01981)
			(layers "*.Cu" "*.Mask")
			(remove_unused_layers no)
			(net "GND")
			(clearance 0)
		)
		(pad "P4_6" thru_hole circle
			(at 5.08 16.51 180)
			(size 1.52781 1.52781)
			(drill 1.01981)
			(layers "*.Cu" "*.Mask")
			(remove_unused_layers no)
			(net "GND")
			(clearance 0)
		)
		(pad "P4_7" thru_hole circle
			(at 2.54 16.51 180)
			(size 1.52781 1.52781)
			(drill 1.01981)
			(layers "*.Cu" "*.Mask")
			(remove_unused_layers no)
			(net "GND")
			(clearance 0)
		)
		(pad "P4_8" thru_hole circle
			(at 0 16.51 180)
			(size 1.52781 1.52781)
			(drill 1.01981)
			(layers "*.Cu" "*.Mask")
			(remove_unused_layers no)
			(net "GND")
			(clearance 0)
		)
		(zone
			(layers "F.Cu" "B.Cu" "In1.Cu" "In2.Cu" "In3.Cu" "In4.Cu" "In5.Cu" "In6.Cu"
				"In7.Cu" "In8.Cu"
			)
			(hatch none 0.5)
			(connect_pads
				(clearance 0)
			)
			(min_thickness 0.25)
			(keepout
				(tracks not_allowed)
				(vias allowed)
				(pads allowed)
				(copperpour not_allowed)
				(footprints allowed)
			)
			(placement
				(enabled no)
				(sheetname "")
			)
			(fill
				(thermal_gap 0.5)
				(thermal_bridge_width 0.5)
				(island_removal_mode 0)
			)
			(polygon
				(pts
					(arc
						(start 212.442298 -79.624936)
						(mid 205.177898 -79.624936)
						(end 212.442298 -79.624936)
					)
				)
			)
		)
		(zone
			(layers "F.Cu" "B.Cu" "In1.Cu" "In2.Cu" "In3.Cu" "In4.Cu" "In5.Cu" "In6.Cu"
				"In7.Cu" "In8.Cu"
			)
			(hatch none 0.5)
			(connect_pads
				(clearance 0)
			)
			(min_thickness 0.25)
			(keepout
				(tracks not_allowed)
				(vias allowed)
				(pads allowed)
				(copperpour not_allowed)
				(footprints allowed)
			)
			(placement
				(enabled no)
				(sheetname "")
			)
			(fill
				(thermal_gap 0.5)
				(thermal_bridge_width 0.5)
				(island_removal_mode 0)
			)
			(polygon
				(pts
					(arc
						(start 212.442298 -22.474936)
						(mid 205.177898 -22.474936)
						(end 212.442298 -22.474936)
					)
				)
			)
		)
		(zone
			(layer "B.Cu")
			(hatch none 0.5)
			(connect_pads
				(clearance 0)
			)
			(min_thickness 0.25)
			(keepout
				(tracks allowed)
				(vias not_allowed)
				(pads allowed)
				(copperpour not_allowed)
				(footprints allowed)
			)
			(placement
				(enabled no)
				(sheetname "")
			)
			(fill
				(thermal_gap 0.5)
				(thermal_bridge_width 0.5)
				(island_removal_mode 0)
			)
			(polygon
				(pts
					(xy 209.637376 -33.712658) (xy 209.637376 -68.387214) (xy 200.36282 -68.387214) (xy 200.36282 -33.712658)
				)
			)
		)
	)
	(footprint ""
		(layer "F.Cu")
		(at 185.117994 -76.35113 180)
		(property "Reference" "R5945"
			(at 0 0 180)
			(layer "F.SilkS")
			(hide yes)
			(effects
				(font
					(size 1.27 1.27)
				)
			)
		)
		(property "Value" ""
			(at 0 0 180)
			(layer "F.Fab")
			(effects
				(font
					(size 1.27 1.27)
				)
			)
		)
		(duplicate_pad_numbers_are_jumpers no)
		(fp_line
			(start 0.7874 0.4064)
			(end -0.7874 0.4064)
			(stroke
				(width 0.1524)
				(type default)
			)
			(layer "F.SilkS")
		)
		(fp_line
			(start 0.7874 -0.4064)
			(end 0.7874 0.4064)
			(stroke
				(width 0.1524)
				(type default)
			)
			(layer "F.SilkS")
		)
		(fp_line
			(start -0.7874 0.4064)
			(end -0.7874 -0.4064)
			(stroke
				(width 0.1524)
				(type default)
			)
			(layer "F.SilkS")
		)
		(fp_line
			(start -0.7874 -0.4064)
			(end 0.7874 -0.4064)
			(stroke
				(width 0.1524)
				(type default)
			)
			(layer "F.SilkS")
		)
		(fp_line
			(start 0.67945 0.3048)
			(end 0.120396 0.3048)
			(stroke
				(width 0.1)
				(type default)
			)
			(layer "F.Fab")
		)
		(fp_line
			(start 0.67945 -0.3048)
			(end 0.67945 0.3048)
			(stroke
				(width 0.1)
				(type default)
			)
			(layer "F.Fab")
		)
		(fp_line
			(start 0.12065 -0.2794)
			(end 0.12065 -0.3048)
			(stroke
				(width 0.1)
				(type default)
			)
			(layer "F.Fab")
		)
		(fp_line
			(start 0.12065 -0.3048)
			(end 0.67945 -0.3048)
			(stroke
				(width 0.1)
				(type default)
			)
			(layer "F.Fab")
		)
		(fp_line
			(start 0.120396 0.3048)
			(end 0.120396 0.2794)
			(stroke
				(width 0.1)
				(type default)
			)
			(layer "F.Fab")
		)
		(fp_line
			(start 0.120396 0.2794)
			(end -0.12065 0.2794)
			(stroke
				(width 0.1)
				(type default)
			)
			(layer "F.Fab")
		)
		(fp_line
			(start -0.12065 0.3048)
			(end -0.67945 0.3048)
			(stroke
				(width 0.1)
				(type default)
			)
			(layer "F.Fab")
		)
		(fp_line
			(start -0.12065 0.2794)
			(end -0.12065 0.3048)
			(stroke
				(width 0.1)
				(type default)
			)
			(layer "F.Fab")
		)
		(fp_line
			(start -0.12065 -0.2794)
			(end 0.12065 -0.2794)
			(stroke
				(width 0.1)
				(type default)
			)
			(layer "F.Fab")
		)
		(fp_line
			(start -0.12065 -0.305054)
			(end -0.12065 -0.2794)
			(stroke
				(width 0.1)
				(type default)
			)
			(layer "F.Fab")
		)
		(fp_line
			(start -0.67945 0.3048)
			(end -0.67945 -0.305054)
			(stroke
				(width 0.1)
				(type default)
			)
			(layer "F.Fab")
		)
		(fp_line
			(start -0.67945 -0.305054)
			(end -0.12065 -0.305054)
			(stroke
				(width 0.1)
				(type default)
			)
			(layer "F.Fab")
		)
		(pad "1" smd circle
			(at -0.40005 0 180)
			(size 0 0)
			(layers "F.Cu" "F.Mask" "F.Paste")
			(net "P3V3_AUX")
		)
		(pad "2" smd circle
			(at 0.40005 0 180)
			(size 0 0)
			(layers "F.Cu" "F.Mask" "F.Paste")
			(net "FM_HS2_EN_FUSE_BUF")
		)
	)
)
